# S9S_MB_2U (Grand Teton) — schematic netlist excerpt (pin names and nets, part order shuffled) for the footprints in the layout excerpt that follows; sources: Cadence DE-HDL packaged netlist, KiCad conversion of 03242023_DA0F0TMBIJ0_F0T_Motherboard_J_brd_V01_OCP.brd

R3860  Q_RES  0 5% EMPTY  pkg 0402LF  page 250 : A = P12V_OCP_V3_2_ISENSE_MPS_MAM ; B = P12V_OCP_V3_2_ISENSE_MAM
R994  Q_RES  33.2 1% CHIP  pkg 0402LF  page 236 : A = SMB_S3M_CPU0_SDA ; B = SMB_S3M_CPU0_R_SDA
C1516  Q_CAP_DIFFBUS  DIFF BUS_0.22UF 6.3V 20% X6S  pkg C0201  page 177 : \1\ = P5E_CPU1_PE3_TX_C_DN<15> ; \2\ = P5E_CPU1_PE3_TX_DN<15>

(kicad_pcb
	(version 20260206)
	(generator "pcbnew")
	(generator_version "10.0")
	(general
		(thickness 1.6)
		(legacy_teardrops no)
	)
	(paper "A4")
	(title_block
		(title "03242023_DA0F0TMBIJ0_F0T_Motherboard_J_brd_V01_OCP.brd")
		(comment 1 "Grand Teton / footprints 45-47 of 6105")
	)
	(layers
		(0 "F.Cu" signal "TOP")
		(4 "In1.Cu" signal "GND")
		(6 "In2.Cu" signal "IN1")
		(8 "In3.Cu" signal "GND1")
		(10 "In4.Cu" signal "IN2")
		(12 "In5.Cu" signal "GND2")
		(14 "In6.Cu" signal "IN3")
		(16 "In7.Cu" signal "GND3")
		(18 "In8.Cu" signal "VCC")
		(20 "In9.Cu" signal "VCC1")
		(22 "In10.Cu" signal "GND4")
		(24 "In11.Cu" signal "IN4")
		(26 "In12.Cu" signal "GND5")
		(28 "In13.Cu" signal "IN5")
		(30 "In14.Cu" signal "GND6")
		(32 "In15.Cu" signal "IN6")
		(34 "In16.Cu" signal "GND7")
		(2 "B.Cu" signal "BOTTOM")
		(9 "F.Adhes" user "F.Adhesive")
		(11 "B.Adhes" user "B.Adhesive")
		(13 "F.Paste" user "Package Geometry/Pastemask Top")
		(15 "B.Paste" user "Package Geometry/Pastemask Bottom")
		(5 "F.SilkS" user "Ref Des/Silkscreen Top")
		(7 "B.SilkS" user "Ref Des/Silkscreen Bottom")
		(1 "F.Mask" user "Board Geometry/Soldermask Top")
		(3 "B.Mask" user "Board Geometry/Soldermask Bottom")
		(17 "Dwgs.User" user "User.Drawings")
		(19 "Cmts.User" user "User.Comments")
		(21 "Eco1.User" user "User.Eco1")
		(23 "Eco2.User" user "User.Eco2")
		(25 "Edge.Cuts" user "Board Geometry/Outline")
		(27 "Margin" user)
		(31 "F.CrtYd" user "Package Geometry/Place Bound Top")
		(29 "B.CrtYd" user "Package Geometry/Place Bound Bottom")
		(35 "F.Fab" user "Ref Des/Assembly Top")
		(33 "B.Fab" user "Ref Des/Assembly Bottom")
	)
	(footprint ""
		(layer "F.Cu")
		(at 29.332428 -98.570034 180)
		(property "Reference" "R3860"
			(at 0 0 180)
			(layer "F.SilkS")
			(hide yes)
			(effects
				(font
					(size 1.27 1.27)
				)
			)
		)
		(property "Value" ""
			(at 0 0 180)
			(layer "F.Fab")
			(effects
				(font
					(size 1.27 1.27)
				)
			)
		)
		(duplicate_pad_numbers_are_jumpers no)
		(fp_line
			(start 0.7874 0.4064)
			(end -0.7874 0.4064)
			(stroke
				(width 0.1524)
				(type default)
			)
			(layer "F.SilkS")
		)
		(fp_line
			(start 0.7874 -0.4064)
			(end 0.7874 0.4064)
			(stroke
				(width 0.1524)
				(type default)
			)
			(layer "F.SilkS")
		)
		(fp_line
			(start -0.7874 0.4064)
			(end -0.7874 -0.4064)
			(stroke
				(width 0.1524)
				(type default)
			)
			(layer "F.SilkS")
		)
		(fp_line
			(start -0.7874 -0.4064)
			(end 0.7874 -0.4064)
			(stroke
				(width 0.1524)
				(type default)
			)
			(layer "F.SilkS")
		)
		(fp_line
			(start 0.67945 0.3048)
			(end 0.120396 0.3048)
			(stroke
				(width 0.1)
				(type default)
			)
			(layer "F.Fab")
		)
		(fp_line
			(start 0.67945 -0.3048)
			(end 0.67945 0.3048)
			(stroke
				(width 0.1)
				(type default)
			)
			(layer "F.Fab")
		)
		(fp_line
			(start 0.12065 -0.2794)
			(end 0.12065 -0.3048)
			(stroke
				(width 0.1)
				(type default)
			)
			(layer "F.Fab")
		)
		(fp_line
			(start 0.12065 -0.3048)
			(end 0.67945 -0.3048)
			(stroke
				(width 0.1)
				(type default)
			)
			(layer "F.Fab")
		)
		(fp_line
			(start 0.120396 0.3048)
			(end 0.120396 0.2794)
			(stroke
				(width 0.1)
				(type default)
			)
			(layer "F.Fab")
		)
		(fp_line
			(start 0.120396 0.2794)
			(end -0.12065 0.2794)
			(stroke
				(width 0.1)
				(type default)
			)
			(layer "F.Fab")
		)
		(fp_line
			(start -0.12065 0.3048)
			(end -0.67945 0.3048)
			(stroke
				(width 0.1)
				(type default)
			)
			(layer "F.Fab")
		)
		(fp_line
			(start -0.12065 0.2794)
			(end -0.12065 0.3048)
			(stroke
				(width 0.1)
				(type default)
			)
			(layer "F.Fab")
		)
		(fp_line
			(start -0.12065 -0.2794)
			(end 0.12065 -0.2794)
			(stroke
				(width 0.1)
				(type default)
			)
			(layer "F.Fab")
		)
		(fp_line
			(start -0.12065 -0.305054)
			(end -0.12065 -0.2794)
			(stroke
				(width 0.1)
				(type default)
			)
			(layer "F.Fab")
		)
		(fp_line
			(start -0.67945 0.3048)
			(end -0.67945 -0.305054)
			(stroke
				(width 0.1)
				(type default)
			)
			(layer "F.Fab")
		)
		(fp_line
			(start -0.67945 -0.305054)
			(end -0.12065 -0.305054)
			(stroke
				(width 0.1)
				(type default)
			)
			(layer "F.Fab")
		)
		(pad "1" smd rect
			(at -0.40005 0)
			(size 0.4572 0.508)
			(layers "F.Cu" "F.Mask" "F.Paste")
			(net "P12V_OCP_V3_2_ISENSE_MPS_MAM")
		)
		(pad "2" smd rect
			(at 0.40005 0)
			(size 0.4572 0.508)
			(layers "F.Cu" "F.Mask" "F.Paste")
			(net "P12V_OCP_V3_2_ISENSE_MAM")
		)
	)
	(footprint ""
		(layer "F.Cu")
		(at 121.475754 -408.517344 -90)
		(property "Reference" "C1516"
			(at 0 0 270)
			(layer "F.SilkS")
			(hide yes)
			(effects
				(font
					(size 1.27 1.27)
				)
			)
		)
		(property "Value" ""
			(at 0 0 270)
			(layer "F.Fab")
			(effects
				(font
					(size 1.27 1.27)
				)
			)
		)
		(duplicate_pad_numbers_are_jumpers no)
		(fp_line
			(start -0.299974 0.150114)
			(end -0.299974 -0.150114)
			(stroke
				(width 0.1)
				(type default)
			)
			(layer "F.Fab")
		)
		(fp_line
			(start 0.299974 0.150114)
			(end -0.299974 0.150114)
			(stroke
				(width 0.1)
				(type default)
			)
			(layer "F.Fab")
		)
		(fp_line
			(start -0.299974 -0.150114)
			(end 0.299974 -0.150114)
			(stroke
				(width 0.1)
				(type default)
			)
			(layer "F.Fab")
		)
		(fp_line
			(start 0.299974 -0.150114)
			(end 0.299974 0.150114)
			(stroke
				(width 0.1)
				(type default)
			)
			(layer "F.Fab")
		)
		(pad "1" smd rect
			(at -0.2667 0 270)
			(size 0.3048 0.381)
			(layers "F.Cu" "F.Mask" "F.Paste")
			(net "P5E_CPU1_PE3_TX_C_DN<15>")
		)
		(pad "2" smd rect
			(at 0.2667 0 270)
			(size 0.3048 0.381)
			(layers "F.Cu" "F.Mask" "F.Paste")
			(net "P5E_CPU1_PE3_TX_DN<15>")
		)
	)
	(footprint ""
		(layer "F.Cu")
		(at 392.763248 -162.360864 -90)
		(property "Reference" "R994"
			(at 0 0 270)
			(layer "F.SilkS")
			(hide yes)
			(effects
				(font
					(size 1.27 1.27)
				)
			)
		)
		(property "Value" ""
			(at 0 0 270)
			(layer "F.Fab")
			(effects
				(font
					(size 1.27 1.27)
				)
			)
		)
		(duplicate_pad_numbers_are_jumpers no)
		(fp_line
			(start -0.7874 0.4064)
			(end -0.7874 -0.4064)
			(stroke
				(width 0.1524)
				(type default)
			)
			(layer "F.SilkS")
		)
		(fp_line
			(start 0.7874 0.4064)
			(end -0.7874 0.4064)
			(stroke
				(width 0.1524)
				(type default)
			)
			(layer "F.SilkS")
		)
		(fp_line
			(start -0.7874 -0.4064)
			(end 0.7874 -0.4064)
			(stroke
				(width 0.1524)
				(type default)
			)
			(layer "F.SilkS")
		)
		(fp_line
			(start 0.7874 -0.4064)
			(end 0.7874 0.4064)
			(stroke
				(width 0.1524)
				(type default)
			)
			(layer "F.SilkS")
		)
		(fp_line
			(start -0.67945 0.3048)
			(end -0.67945 -0.305054)
			(stroke
				(width 0.1)
				(type default)
			)
			(layer "F.Fab")
		)
		(fp_line
			(start -0.12065 0.3048)
			(end -0.67945 0.3048)
			(stroke
				(width 0.1)
				(type default)
			)
			(layer "F.Fab")
		)
		(fp_line
			(start 0.120396 0.3048)
			(end 0.120396 0.2794)
			(stroke
				(width 0.1)
				(type default)
			)
			(layer "F.Fab")
		)
		(fp_line
			(start 0.67945 0.3048)
			(end 0.120396 0.3048)
			(stroke
				(width 0.1)
				(type default)
			)
			(layer "F.Fab")
		)
		(fp_line
			(start -0.12065 0.2794)
			(end -0.12065 0.3048)
			(stroke
				(width 0.1)
				(type default)
			)
			(layer "F.Fab")
		)
		(fp_line
			(start 0.120396 0.2794)
			(end -0.12065 0.2794)
			(stroke
				(width 0.1)
				(type default)
			)
			(layer "F.Fab")
		)
		(fp_line
			(start -0.12065 -0.2794)
			(end 0.12065 -0.2794)
			(stroke
				(width 0.1)
				(type default)
			)
			(layer "F.Fab")
		)
		(fp_line
			(start 0.12065 -0.2794)
			(end 0.12065 -0.3048)
			(stroke
				(width 0.1)
				(type default)
			)
			(layer "F.Fab")
		)
		(fp_line
			(start 0.12065 -0.3048)
			(end 0.67945 -0.3048)
			(stroke
				(width 0.1)
				(type default)
			)
			(layer "F.Fab")
		)
		(fp_line
			(start 0.67945 -0.3048)
			(end 0.67945 0.3048)
			(stroke
				(width 0.1)
				(type default)
			)
			(layer "F.Fab")
		)
		(fp_line
			(start -0.67945 -0.305054)
			(end -0.12065 -0.305054)
			(stroke
				(width 0.1)
				(type default)
			)
			(layer "F.Fab")
		)
		(fp_line
			(start -0.12065 -0.305054)
			(end -0.12065 -0.2794)
			(stroke
				(width 0.1)
				(type default)
			)
			(layer "F.Fab")
		)
		(pad "1" smd circle
			(at -0.40005 0 270)
			(size 0 0)
			(layers "F.Cu" "F.Mask" "F.Paste")
			(net "SMB_S3M_CPU0_SDA")
		)
		(pad "2" smd circle
			(at 0.40005 0 270)
			(size 0 0)
			(layers "F.Cu" "F.Mask" "F.Paste")
			(net "SMB_S3M_CPU0_R_SDA")
		)
	)
)
